(kicad_pcb
	(version 20260206)
	(generator "pcbnew")
	(generator_version "10.0")
	(general
		(thickness 1.6)
		(legacy_teardrops no)
	)
	(paper "A4")
	(title_block
		(title "Bryce Canyon_IOM_IOC_16318-2_OCP.brd")
		(comment 1 "Bryce Canyon / footprints 130-136 of 1605")
	)
	(layers
		(0 "F.Cu" signal "TOP")
		(4 "In1.Cu" signal "L2GND")
		(6 "In2.Cu" signal "L3")
		(8 "In3.Cu" signal "L4VCC")
		(10 "In4.Cu" signal "L5VCC")
		(12 "In5.Cu" signal "L6")
		(14 "In6.Cu" signal "L7GND")
		(2 "B.Cu" signal "BOTTOM")
		(9 "F.Adhes" user "F.Adhesive")
		(11 "B.Adhes" user "B.Adhesive")
		(13 "F.Paste" user "Package Geometry/Pastemask Top")
		(15 "B.Paste" user "Package Geometry/Pastemask Bottom")
		(5 "F.SilkS" user "Ref Des/Silkscreen Top")
		(7 "B.SilkS" user "Ref Des/Silkscreen Bottom")
		(1 "F.Mask" user "Board Geometry/Soldermask Top")
		(3 "B.Mask" user "Board Geometry/Soldermask Bottom")
		(17 "Dwgs.User" user "User.Drawings")
		(19 "Cmts.User" user "User.Comments")
		(21 "Eco1.User" user "User.Eco1")
		(23 "Eco2.User" user "User.Eco2")
		(25 "Edge.Cuts" user "Board Geometry/Outline")
		(27 "Margin" user)
		(31 "F.CrtYd" user "Package Geometry/Place Bound Top")
		(29 "B.CrtYd" user "Package Geometry/Place Bound Bottom")
		(35 "F.Fab" user "Ref Des/Assembly Top")
		(33 "B.Fab" user "Ref Des/Assembly Bottom")
	)
	(footprint ""
		(layer "F.Cu")
		(at 194.3862 -26.162 180)
		(property "Reference" "U48"
			(at 0 0 180)
			(layer "F.SilkS")
			(hide yes)
			(effects
				(font
					(size 1.27 1.27)
				)
			)
		)
		(property "Value" "SN74LVC1G08DCKR-GP"
			(at -2.3368 -8.6868 180)
			(unlocked yes)
			(layer "F.Fab")
			(hide yes)
			(effects
				(font
					(size 1.016 1.016)
					(thickness 0.1524)
				)
			)
		)
		(property "Device Type" "SC70-5H44"
			(at -2.3114 -10.414 180)
			(unlocked yes)
			(layer "F.Fab")
			(hide yes)
			(effects
				(font
					(size 1.016 1.016)
					(thickness 0.1524)
				)
			)
		)
		(duplicate_pad_numbers_are_jumpers no)
		(fp_line
			(start 1.3843 -1.8034)
			(end 1.3843 -1.1176)
			(stroke
				(width 0.3302)
				(type default)
			)
			(layer "F.SilkS")
		)
		(fp_line
			(start 1.27 1.7018)
			(end -1.27 1.7018)
			(stroke
				(width 0.1524)
				(type default)
			)
			(layer "F.SilkS")
		)
		(fp_line
			(start 1.27 -1.7018)
			(end 1.27 1.7018)
			(stroke
				(width 0.1524)
				(type default)
			)
			(layer "F.SilkS")
		)
		(fp_line
			(start 0.6604 -1.8034)
			(end 1.3843 -1.8034)
			(stroke
				(width 0.3302)
				(type default)
			)
			(layer "F.SilkS")
		)
		(fp_line
			(start -1.27 1.7018)
			(end -1.27 -1.7018)
			(stroke
				(width 0.1524)
				(type default)
			)
			(layer "F.SilkS")
		)
		(fp_line
			(start -1.27 -1.7018)
			(end 1.27 -1.7018)
			(stroke
				(width 0.1524)
				(type default)
			)
			(layer "F.SilkS")
		)
		(fp_rect
			(start -1.524 1.9558)
			(end 1.524 -1.9558)
			(stroke
				(width 0)
				(type default)
			)
			(fill no)
			(layer "F.CrtYd")
		)
		(fp_poly
			(pts
				(xy -1.524 -1.9558) (xy 1.524 -1.9558) (xy 1.524 1.9558) (xy -1.524 1.9558)
			)
			(stroke
				(width 0)
				(type default)
			)
			(fill no)
			(layer "F.Fab")
		)
		(pad "1" smd rect
			(at 0.65024 -0.8255 180)
			(size 0.4064 1.2192)
			(layers "F.Cu" "F.Mask" "F.Paste")
			(net "BMC_EXT1_LED_Y")
		)
		(pad "2" smd rect
			(at 0 -0.8255 180)
			(size 0.4064 1.2192)
			(layers "F.Cu" "F.Mask" "F.Paste")
			(net "IOC_EXT1_LED_B")
		)
		(pad "3" smd rect
			(at -0.65024 -0.8255 180)
			(size 0.4064 1.2192)
			(layers "F.Cu" "F.Mask" "F.Paste")
			(net "GND")
		)
		(pad "4" smd rect
			(at -0.65024 0.8255 180)
			(size 0.4064 1.2192)
			(layers "F.Cu" "F.Mask" "F.Paste")
			(net "EXT1_LED_BLUE_G_Q24")
		)
		(pad "5" smd rect
			(at 0.65024 0.8255 180)
			(size 0.4064 1.2192)
			(layers "F.Cu" "F.Mask" "F.Paste")
			(net "P1V8")
		)
	)
	(footprint ""
		(layer "F.Cu")
		(at 199.176894 -31.77921)
		(property "Reference" "R730"
			(at 0 0 0)
			(layer "F.SilkS")
			(hide yes)
			(effects
				(font
					(size 1.27 1.27)
				)
			)
		)
		(property "Value" "1KR2F-3-GP"
			(at 0.064008 -3.993896 0)
			(unlocked yes)
			(layer "F.Fab")
			(hide yes)
			(effects
				(font
					(size 1.016 1.016)
					(thickness 0.1524)
				)
			)
		)
		(property "Device Type" "R402H16"
			(at 0.064008 -5.517896 0)
			(unlocked yes)
			(layer "F.Fab")
			(hide yes)
			(effects
				(font
					(size 1.016 1.016)
					(thickness 0.1524)
				)
			)
		)
		(duplicate_pad_numbers_are_jumpers no)
		(fp_line
			(start -0.508 -0.9398)
			(end -0.508 0.9398)
			(stroke
				(width 0.1524)
				(type default)
			)
			(layer "F.SilkS")
		)
		(fp_line
			(start 0.508 -0.9398)
			(end -0.508 -0.9398)
			(stroke
				(width 0.1524)
				(type default)
			)
			(layer "F.SilkS")
		)
		(fp_rect
			(start -0.508 0.9398)
			(end 0.508 -0.9398)
			(stroke
				(width 0)
				(type default)
			)
			(fill no)
			(layer "F.CrtYd")
		)
		(fp_rect
			(start -0.508 0.9398)
			(end 0.508 -0.9398)
			(stroke
				(width 0)
				(type default)
			)
			(fill no)
			(layer "F.Fab")
		)
		(pad "1" smd custom
			(at 0 -0.4445)
			(size 0.1397 0.1397)
			(layers "F.Cu" "F.Mask" "F.Paste")
			(net "P5V_STBY")
			(options
				(clearance outline)
				(anchor circle)
			)
			(primitives
				(gr_poly
					(pts
						(arc
							(start -0.1778 -0.2794)
							(mid -0.249642 -0.249642)
							(end -0.2794 -0.1778)
						)
						(arc
							(start -0.2794 0.1778)
							(mid -0.249642 0.249642)
							(end -0.1778 0.2794)
						)
						(arc
							(start 0.1778 0.2794)
							(mid 0.249642 0.249642)
							(end 0.2794 0.1778)
						)
						(arc
							(start 0.2794 -0.1778)
							(mid 0.249642 -0.249642)
							(end 0.1778 -0.2794)
						)
					)
					(width 0)
					(fill yes)
				)
			)
		)
		(pad "2" smd custom
			(at 0 0.4445)
			(size 0.1397 0.1397)
			(layers "F.Cu" "F.Mask" "F.Paste")
			(net "EXT2_LED_BLUE_G2")
			(options
				(clearance outline)
				(anchor circle)
			)
			(primitives
				(gr_poly
					(pts
						(arc
							(start -0.1778 -0.2794)
							(mid -0.249642 -0.249642)
							(end -0.2794 -0.1778)
						)
						(arc
							(start -0.2794 0.1778)
							(mid -0.249642 0.249642)
							(end -0.1778 0.2794)
						)
						(arc
							(start 0.1778 0.2794)
							(mid 0.249642 0.249642)
							(end 0.2794 0.1778)
						)
						(arc
							(start 0.2794 -0.1778)
							(mid 0.249642 -0.249642)
							(end 0.1778 -0.2794)
						)
					)
					(width 0)
					(fill yes)
				)
			)
		)
	)
	(footprint ""
		(layer "F.Cu")
		(at 79.840582 -135.980678 90)
		(property "Reference" "R98"
			(at 0 0 90)
			(layer "F.SilkS")
			(hide yes)
			(effects
				(font
					(size 1.27 1.27)
				)
			)
		)
		(property "Value" "0R2J-2-GP"
			(at 0.064008 -3.993896 90)
			(unlocked yes)
			(layer "F.Fab")
			(hide yes)
			(effects
				(font
					(size 1.016 1.016)
					(thickness 0.1524)
				)
			)
		)
		(property "Device Type" "R402H16"
			(at 0.064008 -5.517896 90)
			(unlocked yes)
			(layer "F.Fab")
			(hide yes)
			(effects
				(font
					(size 1.016 1.016)
					(thickness 0.1524)
				)
			)
		)
		(duplicate_pad_numbers_are_jumpers no)
		(fp_line
			(start 0.508 -0.9398)
			(end -0.508 -0.9398)
			(stroke
				(width 0.1524)
				(type default)
			)
			(layer "F.SilkS")
		)
		(fp_line
			(start -0.508 -0.9398)
			(end -0.508 0.9398)
			(stroke
				(width 0.1524)
				(type default)
			)
			(layer "F.SilkS")
		)
		(fp_rect
			(start -0.508 0.9398)
			(end 0.508 -0.9398)
			(stroke
				(width 0)
				(type default)
			)
			(fill no)
			(layer "F.CrtYd")
		)
		(fp_rect
			(start -0.508 0.9398)
			(end 0.508 -0.9398)
			(stroke
				(width 0)
				(type default)
			)
			(fill no)
			(layer "F.Fab")
		)
		(pad "1" smd custom
			(at 0 -0.4445 90)
			(size 0.1397 0.1397)
			(layers "F.Cu" "F.Mask" "F.Paste")
			(net "UART_SEL_MUX")
			(options
				(clearance outline)
				(anchor circle)
			)
			(primitives
				(gr_poly
					(pts
						(arc
							(start -0.1778 -0.2794)
							(mid -0.249642 -0.249642)
							(end -0.2794 -0.1778)
						)
						(arc
							(start -0.2794 0.1778)
							(mid -0.249642 0.249642)
							(end -0.1778 0.2794)
						)
						(arc
							(start 0.1778 0.2794)
							(mid 0.249642 0.249642)
							(end 0.2794 0.1778)
						)
						(arc
							(start 0.2794 -0.1778)
							(mid 0.249642 -0.249642)
							(end 0.1778 -0.2794)
						)
					)
					(width 0)
					(fill yes)
				)
			)
		)
		(pad "2" smd custom
			(at 0 0.4445 90)
			(size 0.1397 0.1397)
			(layers "F.Cu" "F.Mask" "F.Paste")
			(net "D_FLIP_Q")
			(options
				(clearance outline)
				(anchor circle)
			)
			(primitives
				(gr_poly
					(pts
						(arc
							(start -0.1778 -0.2794)
							(mid -0.249642 -0.249642)
							(end -0.2794 -0.1778)
						)
						(arc
							(start -0.2794 0.1778)
							(mid -0.249642 0.249642)
							(end -0.1778 0.2794)
						)
						(arc
							(start 0.1778 0.2794)
							(mid 0.249642 0.249642)
							(end 0.2794 0.1778)
						)
						(arc
							(start 0.2794 -0.1778)
							(mid 0.249642 -0.249642)
							(end 0.1778 -0.2794)
						)
					)
					(width 0)
					(fill yes)
				)
			)
		)
	)
	(footprint ""
		(layer "F.Cu")
		(at 151.1808 -94.8182 90)
		(property "Reference" "R639"
			(at 0 0 90)
			(layer "F.SilkS")
			(hide yes)
			(effects
				(font
					(size 1.27 1.27)
				)
			)
		)
		(property "Value" "4K7R2F-GP"
			(at 0.064008 -3.993896 90)
			(unlocked yes)
			(layer "F.Fab")
			(hide yes)
			(effects
				(font
					(size 1.016 1.016)
					(thickness 0.1524)
				)
			)
		)
		(property "Device Type" "R402H16"
			(at 0.064008 -5.517896 90)
			(unlocked yes)
			(layer "F.Fab")
			(hide yes)
			(effects
				(font
					(size 1.016 1.016)
					(thickness 0.1524)
				)
			)
		)
		(duplicate_pad_numbers_are_jumpers no)
		(fp_line
			(start 0.508 -0.9398)
			(end -0.508 -0.9398)
			(stroke
				(width 0.1524)
				(type default)
			)
			(layer "F.SilkS")
		)
		(fp_line
			(start -0.508 -0.9398)
			(end -0.508 0.9398)
			(stroke
				(width 0.1524)
				(type default)
			)
			(layer "F.SilkS")
		)
		(fp_rect
			(start -0.508 0.9398)
			(end 0.508 -0.9398)
			(stroke
				(width 0)
				(type default)
			)
			(fill no)
			(layer "F.CrtYd")
		)
		(fp_rect
			(start -0.508 0.9398)
			(end 0.508 -0.9398)
			(stroke
				(width 0)
				(type default)
			)
			(fill no)
			(layer "F.Fab")
		)
		(pad "1" smd custom
			(at 0 -0.4445 90)
			(size 0.1397 0.1397)
			(layers "F.Cu" "F.Mask" "F.Paste")
			(net "P3V3_STBY_G")
			(options
				(clearance outline)
				(anchor circle)
			)
			(primitives
				(gr_poly
					(pts
						(arc
							(start -0.1778 -0.2794)
							(mid -0.249642 -0.249642)
							(end -0.2794 -0.1778)
						)
						(arc
							(start -0.2794 0.1778)
							(mid -0.249642 0.249642)
							(end -0.1778 0.2794)
						)
						(arc
							(start 0.1778 0.2794)
							(mid 0.249642 0.249642)
							(end 0.2794 0.1778)
						)
						(arc
							(start 0.2794 -0.1778)
							(mid 0.249642 -0.249642)
							(end 0.1778 -0.2794)
						)
					)
					(width 0)
					(fill yes)
				)
			)
		)
		(pad "2" smd custom
			(at 0 0.4445 90)
			(size 0.1397 0.1397)
			(layers "F.Cu" "F.Mask" "F.Paste")
			(net "P3V3_STBY")
			(options
				(clearance outline)
				(anchor circle)
			)
			(primitives
				(gr_poly
					(pts
						(arc
							(start -0.1778 -0.2794)
							(mid -0.249642 -0.249642)
							(end -0.2794 -0.1778)
						)
						(arc
							(start -0.2794 0.1778)
							(mid -0.249642 0.249642)
							(end -0.1778 0.2794)
						)
						(arc
							(start 0.1778 0.2794)
							(mid 0.249642 0.249642)
							(end 0.2794 0.1778)
						)
						(arc
							(start 0.2794 -0.1778)
							(mid 0.249642 -0.249642)
							(end 0.1778 -0.2794)
						)
					)
					(width 0)
					(fill yes)
				)
			)
		)
	)
	(footprint ""
		(layer "F.Cu")
		(at 160.687512 -141.307058)
		(property "Reference" "R513"
			(at 0 0 0)
			(layer "F.SilkS")
			(hide yes)
			(effects
				(font
					(size 1.27 1.27)
				)
			)
		)
		(property "Value" "10KR2F-2-GP"
			(at 0.064008 -3.993896 0)
			(unlocked yes)
			(layer "F.Fab")
			(hide yes)
			(effects
				(font
					(size 1.016 1.016)
					(thickness 0.1524)
				)
			)
		)
		(property "Device Type" "R402H16"
			(at 0.064008 -5.517896 0)
			(unlocked yes)
			(layer "F.Fab")
			(hide yes)
			(effects
				(font
					(size 1.016 1.016)
					(thickness 0.1524)
				)
			)
		)
		(duplicate_pad_numbers_are_jumpers no)
		(fp_line
			(start -0.508 -0.9398)
			(end -0.508 0.9398)
			(stroke
				(width 0.1524)
				(type default)
			)
			(layer "F.SilkS")
		)
		(fp_line
			(start 0.508 -0.9398)
			(end -0.508 -0.9398)
			(stroke
				(width 0.1524)
				(type default)
			)
			(layer "F.SilkS")
		)
		(fp_rect
			(start -0.508 0.9398)
			(end 0.508 -0.9398)
			(stroke
				(width 0)
				(type default)
			)
			(fill no)
			(layer "F.CrtYd")
		)
		(fp_rect
			(start -0.508 0.9398)
			(end 0.508 -0.9398)
			(stroke
				(width 0)
				(type default)
			)
			(fill no)
			(layer "F.Fab")
		)
		(pad "1" smd custom
			(at 0 -0.4445)
			(size 0.1397 0.1397)
			(layers "F.Cu" "F.Mask" "F.Paste")
			(net "AGND_P1V8_STBY")
			(options
				(clearance outline)
				(anchor circle)
			)
			(primitives
				(gr_poly
					(pts
						(arc
							(start -0.1778 -0.2794)
							(mid -0.249642 -0.249642)
							(end -0.2794 -0.1778)
						)
						(arc
							(start -0.2794 0.1778)
							(mid -0.249642 0.249642)
							(end -0.1778 0.2794)
						)
						(arc
							(start 0.1778 0.2794)
							(mid 0.249642 0.249642)
							(end 0.2794 0.1778)
						)
						(arc
							(start 0.2794 -0.1778)
							(mid 0.249642 -0.249642)
							(end 0.1778 -0.2794)
						)
					)
					(width 0)
					(fill yes)
				)
			)
		)
		(pad "2" smd custom
			(at 0 0.4445)
			(size 0.1397 0.1397)
			(layers "F.Cu" "F.Mask" "F.Paste")
			(net "P1V8_STBY_VFB")
			(options
				(clearance outline)
				(anchor circle)
			)
			(primitives
				(gr_poly
					(pts
						(arc
							(start -0.1778 -0.2794)
							(mid -0.249642 -0.249642)
							(end -0.2794 -0.1778)
						)
						(arc
							(start -0.2794 0.1778)
							(mid -0.249642 0.249642)
							(end -0.1778 0.2794)
						)
						(arc
							(start 0.1778 0.2794)
							(mid 0.249642 0.249642)
							(end 0.2794 0.1778)
						)
						(arc
							(start 0.2794 -0.1778)
							(mid 0.249642 -0.249642)
							(end 0.1778 -0.2794)
						)
					)
					(width 0)
					(fill yes)
				)
			)
		)
	)
	(footprint ""
		(layer "F.Cu")
		(at 199.898 -17.907)
		(property "Reference" "Q21"
			(at 0 0 0)
			(layer "F.SilkS")
			(hide yes)
			(effects
				(font
					(size 1.27 1.27)
				)
			)
		)
		(property "Value" "SSM3K324R-GP"
			(at 0.127 -8.9662 0)
			(unlocked yes)
			(layer "F.Fab")
			(hide yes)
			(effects
				(font
					(size 1.016 1.016)
					(thickness 0.1524)
				)
			)
		)
		(property "Device Type" "SOT23DGS2D4H35"
			(at 0.127 -10.4902 0)
			(unlocked yes)
			(layer "F.Fab")
			(hide yes)
			(effects
				(font
					(size 1.016 1.016)
					(thickness 0.1524)
				)
			)
		)
		(duplicate_pad_numbers_are_jumpers no)
		(fp_line
			(start -1.651 -1.778)
			(end -1.651 1.778)
			(stroke
				(width 0.1524)
				(type default)
			)
			(layer "F.SilkS")
		)
		(fp_line
			(start -1.651 1.778)
			(end 1.651 1.778)
			(stroke
				(width 0.1524)
				(type default)
			)
			(layer "F.SilkS")
		)
		(fp_line
			(start 1.651 -1.778)
			(end -1.651 -1.778)
			(stroke
				(width 0.1524)
				(type default)
			)
			(layer "F.SilkS")
		)
		(fp_line
			(start 1.651 1.778)
			(end 1.651 -1.778)
			(stroke
				(width 0.1524)
				(type default)
			)
			(layer "F.SilkS")
		)
		(fp_poly
			(pts
				(xy -1.778 1.8796) (xy -1.778 -1.8796) (xy 1.778 -1.8796) (xy 1.778 1.8796)
			)
			(stroke
				(width 0)
				(type default)
			)
			(fill no)
			(layer "F.CrtYd")
		)
		(fp_poly
			(pts
				(xy -1.778 1.8796) (xy -1.778 -1.8796) (xy 1.778 -1.8796) (xy 1.778 1.8796)
			)
			(stroke
				(width 0)
				(type default)
			)
			(fill no)
			(layer "F.Fab")
		)
		(pad "D" smd custom
			(at 0 -0.9525)
			(size 0.1905 0.1905)
			(layers "F.Cu" "F.Mask" "F.Paste")
			(net "EXT1_LED_YELLOW_D")
			(options
				(clearance outline)
				(anchor circle)
			)
			(primitives
				(gr_poly
					(pts
						(arc
							(start -0.1778 0.5715)
							(mid -0.321484 0.511984)
							(end -0.381 0.3683)
						)
						(arc
							(start -0.381 -0.3683)
							(mid -0.321484 -0.511984)
							(end -0.1778 -0.5715)
						)
						(arc
							(start 0.1778 -0.5715)
							(mid 0.321484 -0.511984)
							(end 0.381 -0.3683)
						)
						(arc
							(start 0.381 0.3683)
							(mid 0.321484 0.511984)
							(end 0.1778 0.5715)
						)
					)
					(width 0)
					(fill yes)
				)
			)
		)
		(pad "G" smd custom
			(at -0.98425 0.9525)
			(size 0.1905 0.1905)
			(layers "F.Cu" "F.Mask" "F.Paste")
			(net "IOC_EXT1_LED_Y_XOR")
			(options
				(clearance outline)
				(anchor circle)
			)
			(primitives
				(gr_poly
					(pts
						(arc
							(start -0.1778 0.5715)
							(mid -0.321484 0.511984)
							(end -0.381 0.3683)
						)
						(arc
							(start -0.381 -0.3683)
							(mid -0.321484 -0.511984)
							(end -0.1778 -0.5715)
						)
						(arc
							(start 0.1778 -0.5715)
							(mid 0.321484 -0.511984)
							(end 0.381 -0.3683)
						)
						(arc
							(start 0.381 0.3683)
							(mid 0.321484 0.511984)
							(end 0.1778 0.5715)
						)
					)
					(width 0)
					(fill yes)
				)
			)
		)
		(pad "S" smd custom
			(at 0.98425 0.9525)
			(size 0.1905 0.1905)
			(layers "F.Cu" "F.Mask" "F.Paste")
			(net "GND")
			(options
				(clearance outline)
				(anchor circle)
			)
			(primitives
				(gr_poly
					(pts
						(arc
							(start -0.1778 0.5715)
							(mid -0.321484 0.511984)
							(end -0.381 0.3683)
						)
						(arc
							(start -0.381 -0.3683)
							(mid -0.321484 -0.511984)
							(end -0.1778 -0.5715)
						)
						(arc
							(start 0.1778 -0.5715)
							(mid 0.321484 -0.511984)
							(end 0.381 -0.3683)
						)
						(arc
							(start 0.381 0.3683)
							(mid 0.321484 0.511984)
							(end 0.1778 0.5715)
						)
					)
					(width 0)
					(fill yes)
				)
			)
		)
	)
	(footprint ""
		(layer "F.Cu")
		(at 50.5714 -127.7112 90)
		(property "Reference" "R87"
			(at 0 0 90)
			(layer "F.SilkS")
			(hide yes)
			(effects
				(font
					(size 1.27 1.27)
				)
			)
		)
		(property "Value" "100KR2F-L1-GP"
			(at 0.064008 -3.993896 90)
			(unlocked yes)
			(layer "F.Fab")
			(hide yes)
			(effects
				(font
					(size 1.016 1.016)
					(thickness 0.1524)
				)
			)
		)
		(property "Device Type" "R402H16"
			(at 0.064008 -5.517896 90)
			(unlocked yes)
			(layer "F.Fab")
			(hide yes)
			(effects
				(font
					(size 1.016 1.016)
					(thickness 0.1524)
				)
			)
		)
		(duplicate_pad_numbers_are_jumpers no)
		(fp_line
			(start 0.508 -0.9398)
			(end -0.508 -0.9398)
			(stroke
				(width 0.1524)
				(type default)
			)
			(layer "F.SilkS")
		)
		(fp_line
			(start -0.508 -0.9398)
			(end -0.508 0.9398)
			(stroke
				(width 0.1524)
				(type default)
			)
			(layer "F.SilkS")
		)
		(fp_rect
			(start -0.508 0.9398)
			(end 0.508 -0.9398)
			(stroke
				(width 0)
				(type default)
			)
			(fill no)
			(layer "F.CrtYd")
		)
		(fp_rect
			(start -0.508 0.9398)
			(end 0.508 -0.9398)
			(stroke
				(width 0)
				(type default)
			)
			(fill no)
			(layer "F.Fab")
		)
		(pad "1" smd custom
			(at 0 -0.4445 90)
			(size 0.1397 0.1397)
			(layers "F.Cu" "F.Mask" "F.Paste")
			(net "SCC_RMT_FULL_PWR_EN")
			(options
				(clearance outline)
				(anchor circle)
			)
			(primitives
				(gr_poly
					(pts
						(arc
							(start -0.1778 -0.2794)
							(mid -0.249642 -0.249642)
							(end -0.2794 -0.1778)
						)
						(arc
							(start -0.2794 0.1778)
							(mid -0.249642 0.249642)
							(end -0.1778 0.2794)
						)
						(arc
							(start 0.1778 0.2794)
							(mid 0.249642 0.249642)
							(end 0.2794 0.1778)
						)
						(arc
							(start 0.2794 -0.1778)
							(mid 0.249642 -0.249642)
							(end 0.1778 -0.2794)
						)
					)
					(width 0)
					(fill yes)
				)
			)
		)
		(pad "2" smd custom
			(at 0 0.4445 90)
			(size 0.1397 0.1397)
			(layers "F.Cu" "F.Mask" "F.Paste")
			(net "GND")
			(options
				(clearance outline)
				(anchor circle)
			)
			(primitives
				(gr_poly
					(pts
						(arc
							(start -0.1778 -0.2794)
							(mid -0.249642 -0.249642)
							(end -0.2794 -0.1778)
						)
						(arc
							(start -0.2794 0.1778)
							(mid -0.249642 0.249642)
							(end -0.1778 0.2794)
						)
						(arc
							(start 0.1778 0.2794)
							(mid 0.249642 0.249642)
							(end 0.2794 0.1778)
						)
						(arc
							(start 0.2794 -0.1778)
							(mid 0.249642 -0.249642)
							(end 0.1778 -0.2794)
						)
					)
					(width 0)
					(fill yes)
				)
			)
		)
	)
)
